(kicad_pcb
	(version 20260206)
	(generator "pcbnew")
	(generator_version "10.0")
	(general
		(thickness 1.6)
		(legacy_teardrops no)
	)
	(paper "A4")
	(title_block
		(title "baseboard — 13948-1b.1110WZS1818.brd")
		(comment 1 "Honey Badger (Wiwynn) / footprints 1645-1651 of 2523")
	)
	(layers
		(0 "F.Cu" signal "TOP")
		(4 "In1.Cu" signal "L2GND")
		(6 "In2.Cu" signal "L3")
		(8 "In3.Cu" signal "L4VCC")
		(10 "In4.Cu" signal "L5VCC")
		(12 "In5.Cu" signal "L6")
		(14 "In6.Cu" signal "L7GND")
		(2 "B.Cu" signal "BOTTOM")
		(9 "F.Adhes" user "F.Adhesive")
		(11 "B.Adhes" user "B.Adhesive")
		(13 "F.Paste" user "Package Geometry/Pastemask Top")
		(15 "B.Paste" user "Package Geometry/Pastemask Bottom")
		(5 "F.SilkS" user "Ref Des/Silkscreen Top")
		(7 "B.SilkS" user "Ref Des/Silkscreen Bottom")
		(1 "F.Mask" user "Board Geometry/Soldermask Top")
		(3 "B.Mask" user "Board Geometry/Soldermask Bottom")
		(17 "Dwgs.User" user "User.Drawings")
		(19 "Cmts.User" user "User.Comments")
		(21 "Eco1.User" user "User.Eco1")
		(23 "Eco2.User" user "User.Eco2")
		(25 "Edge.Cuts" user "Board Geometry/Outline")
		(27 "Margin" user)
		(31 "F.CrtYd" user "Package Geometry/Place Bound Top")
		(29 "B.CrtYd" user "Package Geometry/Place Bound Bottom")
		(35 "F.Fab" user "Ref Des/Assembly Top")
		(33 "B.Fab" user "Ref Des/Assembly Bottom")
	)
	(footprint ""
		(layer "F.Cu")
		(at 334.518 -217.3605)
		(property "Reference" "R5302"
			(at 0 0 0)
			(layer "F.SilkS")
			(hide yes)
			(effects
				(font
					(size 1.27 1.27)
				)
			)
		)
		(property "Value" "0R2J-2-GP"
			(at 0.064008 -3.993896 0)
			(unlocked yes)
			(layer "F.Fab")
			(hide yes)
			(effects
				(font
					(size 1.016 1.016)
					(thickness 0.1524)
				)
			)
		)
		(property "Device Type" "R402H16"
			(at 0.064008 -5.517896 0)
			(unlocked yes)
			(layer "F.Fab")
			(hide yes)
			(effects
				(font
					(size 1.016 1.016)
					(thickness 0.1524)
				)
			)
		)
		(duplicate_pad_numbers_are_jumpers no)
		(fp_line
			(start -0.508 -0.9398)
			(end -0.508 0.9398)
			(stroke
				(width 0.1524)
				(type default)
			)
			(layer "F.SilkS")
		)
		(fp_line
			(start 0.508 -0.9398)
			(end -0.508 -0.9398)
			(stroke
				(width 0.1524)
				(type default)
			)
			(layer "F.SilkS")
		)
		(fp_rect
			(start -0.508 0.9398)
			(end 0.508 -0.9398)
			(stroke
				(width 0)
				(type default)
			)
			(fill no)
			(layer "F.CrtYd")
		)
		(fp_rect
			(start -0.508 0.9398)
			(end 0.508 -0.9398)
			(stroke
				(width 0)
				(type default)
			)
			(fill no)
			(layer "F.Fab")
		)
		(pad "1" smd custom
			(at 0 -0.4445)
			(size 0.1397 0.1397)
			(layers "F.Cu" "F.Mask" "F.Paste")
			(net "VOL_SEN_SDA")
			(options
				(clearance outline)
				(anchor circle)
			)
			(primitives
				(gr_poly
					(pts
						(arc
							(start -0.1778 -0.2794)
							(mid -0.249642 -0.249642)
							(end -0.2794 -0.1778)
						)
						(arc
							(start -0.2794 0.1778)
							(mid -0.249642 0.249642)
							(end -0.1778 0.2794)
						)
						(arc
							(start 0.1778 0.2794)
							(mid 0.249642 0.249642)
							(end 0.2794 0.1778)
						)
						(arc
							(start 0.2794 -0.1778)
							(mid 0.249642 -0.249642)
							(end 0.1778 -0.2794)
						)
					)
					(width 0)
					(fill yes)
				)
			)
		)
		(pad "2" smd custom
			(at 0 0.4445)
			(size 0.1397 0.1397)
			(layers "F.Cu" "F.Mask" "F.Paste")
			(net "BMC_I2C_SDA_10")
			(options
				(clearance outline)
				(anchor circle)
			)
			(primitives
				(gr_poly
					(pts
						(arc
							(start -0.1778 -0.2794)
							(mid -0.249642 -0.249642)
							(end -0.2794 -0.1778)
						)
						(arc
							(start -0.2794 0.1778)
							(mid -0.249642 0.249642)
							(end -0.1778 0.2794)
						)
						(arc
							(start 0.1778 0.2794)
							(mid 0.249642 0.249642)
							(end 0.2794 0.1778)
						)
						(arc
							(start 0.2794 -0.1778)
							(mid 0.249642 -0.249642)
							(end 0.1778 -0.2794)
						)
					)
					(width 0)
					(fill yes)
				)
			)
		)
	)
	(footprint ""
		(layer "F.Cu")
		(at 329.429872 -164.029136 -90)
		(property "Reference" "U26"
			(at 0 0 270)
			(layer "F.SilkS")
			(hide yes)
			(effects
				(font
					(size 1.27 1.27)
				)
			)
		)
		(property "Value" "TS5A23157DGSR-GP"
			(at 0 -11.1252 270)
			(unlocked yes)
			(layer "F.Fab")
			(hide yes)
			(effects
				(font
					(size 1.016 1.016)
					(thickness 0.1524)
				)
			)
		)
		(property "Device Type" "MSOP10H44"
			(at 0 -12.6492 270)
			(unlocked yes)
			(layer "F.Fab")
			(hide yes)
			(effects
				(font
					(size 1.016 1.016)
					(thickness 0.1524)
				)
			)
		)
		(duplicate_pad_numbers_are_jumpers no)
		(fp_line
			(start -2.0066 1.016)
			(end -2.0066 -1.016)
			(stroke
				(width 0.1524)
				(type default)
			)
			(layer "F.SilkS")
		)
		(fp_line
			(start -1.8288 1.016)
			(end -1.8288 3.048)
			(stroke
				(width 0.508)
				(type default)
			)
			(layer "F.SilkS")
		)
		(fp_line
			(start 1.143 1.016)
			(end -2.0066 1.016)
			(stroke
				(width 0.1524)
				(type default)
			)
			(layer "F.SilkS")
		)
		(fp_line
			(start -1.5748 0)
			(end -1.9558 0.381)
			(stroke
				(width 0.1524)
				(type default)
			)
			(layer "F.SilkS")
		)
		(fp_line
			(start -1.5748 0)
			(end -1.9558 -0.381)
			(stroke
				(width 0.1524)
				(type default)
			)
			(layer "F.SilkS")
		)
		(fp_line
			(start -2.0066 -1.016)
			(end 1.143 -1.016)
			(stroke
				(width 0.1524)
				(type default)
			)
			(layer "F.SilkS")
		)
		(fp_line
			(start 1.143 -1.016)
			(end 1.143 1.016)
			(stroke
				(width 0.1524)
				(type default)
			)
			(layer "F.SilkS")
		)
		(fp_poly
			(pts
				(xy -2.0828 3.3401) (xy 2.0828 3.3401) (xy 2.0828 -3.3401) (xy -2.0828 -3.3401)
			)
			(stroke
				(width 0)
				(type default)
			)
			(fill no)
			(layer "F.CrtYd")
		)
		(fp_poly
			(pts
				(xy -2.0828 3.3401) (xy 2.0828 3.3401) (xy 2.0828 -3.3401) (xy -2.0828 -3.3401)
			)
			(stroke
				(width 0)
				(type default)
			)
			(fill no)
			(layer "F.Fab")
		)
		(pad "1" smd rect
			(at -0.99949 2.0701 270)
			(size 0.3048 1.524)
			(layers "F.Cu" "F.Mask" "F.Paste")
			(net "BMC_UART_SWITCH_1R")
		)
		(pad "2" smd rect
			(at -0.50038 2.0701 270)
			(size 0.3048 1.524)
			(layers "F.Cu" "F.Mask" "F.Paste")
			(net "IOC_UART_TX")
		)
		(pad "3" smd rect
			(at 0 2.0701 270)
			(size 0.3048 1.524)
			(layers "F.Cu" "F.Mask" "F.Paste")
			(net "GND")
		)
		(pad "4" smd rect
			(at 0.50038 2.0701 270)
			(size 0.3048 1.524)
			(layers "F.Cu" "F.Mask" "F.Paste")
			(net "IOC_UART_RX")
		)
		(pad "5" smd rect
			(at 0.99949 2.0701 270)
			(size 0.3048 1.524)
			(layers "F.Cu" "F.Mask" "F.Paste")
			(net "BMC_UART_SWITCH_1R")
		)
		(pad "6" smd rect
			(at 0.99949 -2.0701 270)
			(size 0.3048 1.524)
			(layers "F.Cu" "F.Mask" "F.Paste")
			(net "UART1_RX")
		)
		(pad "7" smd rect
			(at 0.50038 -2.0701 270)
			(size 0.3048 1.524)
			(layers "F.Cu" "F.Mask" "F.Paste")
			(net "CPU_UART_RX_R")
		)
		(pad "8" smd rect
			(at 0 -2.0701 270)
			(size 0.3048 1.524)
			(layers "F.Cu" "F.Mask" "F.Paste")
			(net "P3V3_STBY")
		)
		(pad "9" smd rect
			(at -0.50038 -2.0701 270)
			(size 0.3048 1.524)
			(layers "F.Cu" "F.Mask" "F.Paste")
			(net "CPU_UART_TX_R")
		)
		(pad "10" smd rect
			(at -0.99949 -2.0701 270)
			(size 0.3048 1.524)
			(layers "F.Cu" "F.Mask" "F.Paste")
			(net "UART1_TX")
		)
	)
	(footprint ""
		(layer "F.Cu")
		(at 86.995 -242.443 180)
		(property "Reference" "SR952"
			(at 0 0 180)
			(layer "F.SilkS")
			(hide yes)
			(effects
				(font
					(size 1.27 1.27)
				)
			)
		)
		(property "Value" "4K7R2F-GP"
			(at 0.064008 -3.993896 180)
			(unlocked yes)
			(layer "F.Fab")
			(hide yes)
			(effects
				(font
					(size 1.016 1.016)
					(thickness 0.1524)
				)
			)
		)
		(property "Device Type" "R402H16"
			(at 0.064008 -5.517896 180)
			(unlocked yes)
			(layer "F.Fab")
			(hide yes)
			(effects
				(font
					(size 1.016 1.016)
					(thickness 0.1524)
				)
			)
		)
		(duplicate_pad_numbers_are_jumpers no)
		(fp_line
			(start 0.508 -0.9398)
			(end -0.508 -0.9398)
			(stroke
				(width 0.1524)
				(type default)
			)
			(layer "F.SilkS")
		)
		(fp_line
			(start -0.508 -0.9398)
			(end -0.508 0.9398)
			(stroke
				(width 0.1524)
				(type default)
			)
			(layer "F.SilkS")
		)
		(fp_rect
			(start -0.508 0.9398)
			(end 0.508 -0.9398)
			(stroke
				(width 0)
				(type default)
			)
			(fill no)
			(layer "F.CrtYd")
		)
		(fp_rect
			(start -0.508 0.9398)
			(end 0.508 -0.9398)
			(stroke
				(width 0)
				(type default)
			)
			(fill no)
			(layer "F.Fab")
		)
		(pad "1" smd custom
			(at 0 -0.4445 180)
			(size 0.1397 0.1397)
			(layers "F.Cu" "F.Mask" "F.Paste")
			(net "SAS_FAULT_LED11")
			(options
				(clearance outline)
				(anchor circle)
			)
			(primitives
				(gr_poly
					(pts
						(arc
							(start -0.1778 -0.2794)
							(mid -0.249642 -0.249642)
							(end -0.2794 -0.1778)
						)
						(arc
							(start -0.2794 0.1778)
							(mid -0.249642 0.249642)
							(end -0.1778 0.2794)
						)
						(arc
							(start 0.1778 0.2794)
							(mid 0.249642 0.249642)
							(end 0.2794 0.1778)
						)
						(arc
							(start 0.2794 -0.1778)
							(mid 0.249642 -0.249642)
							(end 0.1778 -0.2794)
						)
					)
					(width 0)
					(fill yes)
				)
			)
		)
		(pad "2" smd custom
			(at 0 0.4445 180)
			(size 0.1397 0.1397)
			(layers "F.Cu" "F.Mask" "F.Paste")
			(net "P3V3_STBY")
			(options
				(clearance outline)
				(anchor circle)
			)
			(primitives
				(gr_poly
					(pts
						(arc
							(start -0.1778 -0.2794)
							(mid -0.249642 -0.249642)
							(end -0.2794 -0.1778)
						)
						(arc
							(start -0.2794 0.1778)
							(mid -0.249642 0.249642)
							(end -0.1778 0.2794)
						)
						(arc
							(start 0.1778 0.2794)
							(mid 0.249642 0.249642)
							(end 0.2794 0.1778)
						)
						(arc
							(start 0.2794 -0.1778)
							(mid 0.249642 -0.249642)
							(end 0.1778 -0.2794)
						)
					)
					(width 0)
					(fill yes)
				)
			)
		)
	)
	(footprint ""
		(layer "F.Cu")
		(at 131.318 -91.313 90)
		(property "Reference" "SC1104"
			(at 0 0 90)
			(layer "F.SilkS")
			(hide yes)
			(effects
				(font
					(size 1.27 1.27)
				)
			)
		)
		(property "Value" "SCD01U10V1KX-GP"
			(at -2.8321 -1.7399 90)
			(unlocked yes)
			(layer "F.Fab")
			(hide yes)
			(effects
				(font
					(size 1.016 1.016)
					(thickness 0.1524)
				)
			)
		)
		(property "Device Type" "C0201H13"
			(at -2.8321 -3.2639 90)
			(unlocked yes)
			(layer "F.Fab")
			(hide yes)
			(effects
				(font
					(size 1.016 1.016)
					(thickness 0.1524)
				)
			)
		)
		(duplicate_pad_numbers_are_jumpers no)
		(fp_rect
			(start -0.2794 0.6477)
			(end 0.2794 -0.6477)
			(stroke
				(width 0)
				(type default)
			)
			(fill no)
			(layer "F.CrtYd")
		)
		(fp_rect
			(start -0.2794 0.6477)
			(end 0.2794 -0.6477)
			(stroke
				(width 0)
				(type default)
			)
			(fill no)
			(layer "F.Fab")
		)
		(pad "1" smd custom
			(at 0 -0.2794 90)
			(size 0.0762 0.0762)
			(layers "F.Cu" "F.Mask" "F.Paste")
			(net "3X24_SAS_TX19_P")
			(options
				(clearance outline)
				(anchor circle)
			)
			(primitives
				(gr_poly
					(pts
						(arc
							(start 0.1524 -0.127)
							(mid 0.137521 -0.162921)
							(end 0.1016 -0.1778)
						)
						(arc
							(start -0.1016 -0.1778)
							(mid -0.137521 -0.162921)
							(end -0.1524 -0.127)
						)
						(arc
							(start -0.1524 0.127)
							(mid -0.137521 0.162921)
							(end -0.1016 0.1778)
						)
						(arc
							(start 0.1016 0.1778)
							(mid 0.137521 0.162921)
							(end 0.1524 0.127)
						)
					)
					(width 0)
					(fill yes)
				)
			)
		)
		(pad "2" smd custom
			(at 0 0.2794 90)
			(size 0.0762 0.0762)
			(layers "F.Cu" "F.Mask" "F.Paste")
			(net "SAS_EXP2CONN_TX_P_23")
			(options
				(clearance outline)
				(anchor circle)
			)
			(primitives
				(gr_poly
					(pts
						(arc
							(start 0.1524 -0.127)
							(mid 0.137521 -0.162921)
							(end 0.1016 -0.1778)
						)
						(arc
							(start -0.1016 -0.1778)
							(mid -0.137521 -0.162921)
							(end -0.1524 -0.127)
						)
						(arc
							(start -0.1524 0.127)
							(mid -0.137521 0.162921)
							(end -0.1016 0.1778)
						)
						(arc
							(start 0.1016 0.1778)
							(mid 0.137521 0.162921)
							(end 0.1524 0.127)
						)
					)
					(width 0)
					(fill yes)
				)
			)
		)
	)
	(footprint ""
		(layer "F.Cu")
		(at 120.847612 -205.867 180)
		(property "Reference" "SR871"
			(at 0 0 180)
			(layer "F.SilkS")
			(hide yes)
			(effects
				(font
					(size 1.27 1.27)
				)
			)
		)
		(property "Value" "0R2J-2-GP"
			(at 0.064008 -3.993896 180)
			(unlocked yes)
			(layer "F.Fab")
			(hide yes)
			(effects
				(font
					(size 1.016 1.016)
					(thickness 0.1524)
				)
			)
		)
		(property "Device Type" "R402H16"
			(at 0.064008 -5.517896 180)
			(unlocked yes)
			(layer "F.Fab")
			(hide yes)
			(effects
				(font
					(size 1.016 1.016)
					(thickness 0.1524)
				)
			)
		)
		(duplicate_pad_numbers_are_jumpers no)
		(fp_line
			(start 0.508 -0.9398)
			(end -0.508 -0.9398)
			(stroke
				(width 0.1524)
				(type default)
			)
			(layer "F.SilkS")
		)
		(fp_line
			(start -0.508 -0.9398)
			(end -0.508 0.9398)
			(stroke
				(width 0.1524)
				(type default)
			)
			(layer "F.SilkS")
		)
		(fp_rect
			(start -0.508 0.9398)
			(end 0.508 -0.9398)
			(stroke
				(width 0)
				(type default)
			)
			(fill no)
			(layer "F.CrtYd")
		)
		(fp_rect
			(start -0.508 0.9398)
			(end 0.508 -0.9398)
			(stroke
				(width 0)
				(type default)
			)
			(fill no)
			(layer "F.Fab")
		)
		(pad "1" smd custom
			(at 0 -0.4445 180)
			(size 0.1397 0.1397)
			(layers "F.Cu" "F.Mask" "F.Paste")
			(net "SAS_HDD_REDV_TX7_P")
			(options
				(clearance outline)
				(anchor circle)
			)
			(primitives
				(gr_poly
					(pts
						(arc
							(start -0.1778 -0.2794)
							(mid -0.249642 -0.249642)
							(end -0.2794 -0.1778)
						)
						(arc
							(start -0.2794 0.1778)
							(mid -0.249642 0.249642)
							(end -0.1778 0.2794)
						)
						(arc
							(start 0.1778 0.2794)
							(mid 0.249642 0.249642)
							(end 0.2794 0.1778)
						)
						(arc
							(start 0.2794 -0.1778)
							(mid 0.249642 -0.249642)
							(end 0.1778 -0.2794)
						)
					)
					(width 0)
					(fill yes)
				)
			)
		)
		(pad "2" smd custom
			(at 0 0.4445 180)
			(size 0.1397 0.1397)
			(layers "F.Cu" "F.Mask" "F.Paste")
			(net "REDV_TX7_P")
			(options
				(clearance outline)
				(anchor circle)
			)
			(primitives
				(gr_poly
					(pts
						(arc
							(start -0.1778 -0.2794)
							(mid -0.249642 -0.249642)
							(end -0.2794 -0.1778)
						)
						(arc
							(start -0.2794 0.1778)
							(mid -0.249642 0.249642)
							(end -0.1778 0.2794)
						)
						(arc
							(start 0.1778 0.2794)
							(mid 0.249642 0.249642)
							(end 0.2794 0.1778)
						)
						(arc
							(start 0.2794 -0.1778)
							(mid 0.249642 -0.249642)
							(end 0.1778 -0.2794)
						)
					)
					(width 0)
					(fill yes)
				)
			)
		)
	)
	(footprint ""
		(layer "F.Cu")
		(at 98.557842 -104.719882)
		(property "Reference" "STP89"
			(at 0 0 0)
			(layer "F.SilkS")
			(hide yes)
			(effects
				(font
					(size 1.27 1.27)
				)
			)
		)
		(property "Value" "TPAD28"
			(at 0.0127 -1.8034 0)
			(unlocked yes)
			(layer "F.Fab")
			(hide yes)
			(effects
				(font
					(size 1.016 1.016)
					(thickness 0.1524)
				)
			)
		)
		(property "Device Type" "TPAD28"
			(at 0.0127 -3.3274 0)
			(unlocked yes)
			(layer "F.Fab")
			(hide yes)
			(effects
				(font
					(size 1.016 1.016)
					(thickness 0.1524)
				)
			)
		)
		(duplicate_pad_numbers_are_jumpers no)
		(fp_poly
			(pts
				(arc
					(start 0.3556 0)
					(mid -0.3556 0)
					(end 0.3556 0)
				)
			)
			(stroke
				(width 0)
				(type default)
			)
			(fill no)
			(layer "F.CrtYd")
		)
		(fp_poly
			(pts
				(arc
					(start 0.6096 0)
					(mid -0.6096 0)
					(end 0.6096 0)
				)
			)
			(stroke
				(width 0)
				(type default)
			)
			(fill no)
			(layer "F.Fab")
		)
		(pad "1" smd circle
			(at 0 0)
			(size 0.7112 0.7112)
			(layers "F.Cu" "F.Mask" "F.Paste")
			(net "UART_RTS")
		)
	)
	(footprint ""
		(layer "F.Cu")
		(at 318.389 -44.704 90)
		(property "Reference" "TC14"
			(at 0 0 90)
			(layer "F.SilkS")
			(hide yes)
			(effects
				(font
					(size 1.27 1.27)
				)
			)
		)
		(property "Value" "SC47U16V0MX-GP"
			(at -0.00254 -4.78536 90)
			(unlocked yes)
			(layer "F.Fab")
			(hide yes)
			(effects
				(font
					(size 1.016 1.016)
					(thickness 0.1524)
				)
			)
		)
		(property "Device Type" "C1210H107"
			(at -0.00254 -6.38048 90)
			(unlocked yes)
			(layer "F.Fab")
			(hide yes)
			(effects
				(font
					(size 1.016 1.016)
					(thickness 0.1524)
				)
			)
		)
		(duplicate_pad_numbers_are_jumpers no)
		(fp_line
			(start 1.5748 -2.3368)
			(end -1.5748 -2.3368)
			(stroke
				(width 0.1524)
				(type default)
			)
			(layer "F.SilkS")
		)
		(fp_line
			(start -1.5748 -2.3368)
			(end -1.5748 -0.762)
			(stroke
				(width 0.1524)
				(type default)
			)
			(layer "F.SilkS")
		)
		(fp_line
			(start 1.5748 -0.762)
			(end 1.5748 -2.3368)
			(stroke
				(width 0.1524)
				(type default)
			)
			(layer "F.SilkS")
		)
		(fp_line
			(start -1.5748 0.762)
			(end -1.5748 2.3368)
			(stroke
				(width 0.1524)
				(type default)
			)
			(layer "F.SilkS")
		)
		(fp_line
			(start 1.5748 2.3368)
			(end 1.5748 0.762)
			(stroke
				(width 0.1524)
				(type default)
			)
			(layer "F.SilkS")
		)
		(fp_line
			(start -1.5748 2.3368)
			(end 1.5748 2.3368)
			(stroke
				(width 0.1524)
				(type default)
			)
			(layer "F.SilkS")
		)
		(fp_rect
			(start -1.651 2.413)
			(end 1.651 -2.413)
			(stroke
				(width 0)
				(type default)
			)
			(fill no)
			(layer "F.CrtYd")
		)
		(fp_poly
			(pts
				(xy 1.651 2.413) (xy 1.651 -2.413) (xy -1.651 -2.413) (xy -1.651 2.413)
			)
			(stroke
				(width 0)
				(type default)
			)
			(fill no)
			(layer "F.Fab")
		)
		(pad "1" smd rect
			(at 0 -1.4732 90)
			(size 2.794 1.397)
			(layers "F.Cu" "F.Mask" "F.Paste")
			(net "P5V_STBY")
		)
		(pad "2" smd rect
			(at 0 1.4732 90)
			(size 2.794 1.397)
			(layers "F.Cu" "F.Mask" "F.Paste")
			(net "GND")
		)
	)
)
